FILE_TYPE = MULTI_PHYS_TABLE;

PART 'TDR_3P'

{========================================================================================}
:PACK_TYPE | MATERIAL | PART_NUMBER    = STANDARD         | LIFECYCLE        | PART_NUMBER | JEDEC_TYPE                 | ALT_SYMBOLS                | CLASS | DESCRIPTION                                 | HEIGHT       | COMPONENT_TYPE | LPID | SPEED_URL ;
{========================================================================================}
 'TH'      | 'EMPTY'  | 'N_A'(!)       = ''               | ''               | 'N_A'       |'TDR_3P_C56P38_Q_EOL'| '(TDR_3P_C22P10)'          | 'IO'  | '(USE SYM_1)TDR PROBE POINT'                | '0.00001 IN' | 'PSEUDO'       | ''   | ''       
 'TH1'     | 'EMPTY'  | 'N_A'(!)       = ''               | ''               | 'N_A'       |'TDR_3P_C85P67_140M_Q_EOL'| '(TDR_3P_C85P67_140M)'     | 'IO'  | '(USE SYM_1)TDR 3PIN 140MIL P2P'            | '0.00001 IN' | 'PSEUDO'       | ''   | ''       
 'TH2'     | 'EMPTY'  | 'N_A'(!)       = ''               | ''               | 'N_A'       |'TDR_3P_C85P67_141_100M_Q'| '(TDR_3P_C85P67_141_100M)' | 'IO'  | '(USE SYM_2)TDR 3PIN,2X141MIL 1X100MIL P2P' | '0.00001 IN' | 'PSEUDO'       | ''   | ''       

END_PART

END.

